FILE_TYPE = CONNECTIVITY;
{Allegro Design Entry HDL 17.2-2016 S081 (4005846) 1/11/2022}
"PAGE_NUMBER" = 80;
0"NC";
1"FM_PWRGD_PVDD33_S5";
2"FM_LED_D2";
3"FM_LED_D3";
4"PVDD11_S3_P1_EN";
5"PWRGD_PVDD11_S3_P1";
6"PVDD18_S5_P1_EN";
7"SPI_PLD_CLK"CDS_PHYS_NET_NAME"SPI_PLD_CLK";
8"SPI_PLD_D1"CDS_PHYS_NET_NAME"SPI_PLD_D1";
9"FM_PVDD18_S5_P0_EN";
10"FM_PWRGD_PVDD18_S5_P0";
11"FM_CPU0_PWR_GOOD";
12"FM_PVDDIO_P1_EN";
13"PWRGD_P1V8_STBY_R";
14"FM_PLD_OCP_SFF_PWR_GOOD_R";
15"P12V_E1S_2_PWRGD";
16"P12V_E1S_1_PWRGD";
17"PWGD_P3V3_E1S_2";
18"FM_PWRGD_PVDDIO_P1";
19"PWRGD_P3V3_STBY_R";
20"PVDD18_S5_P1_R_EN";
21"BMC_HPM_FPGA_LED2";
22"PWRGD_PVDDIO_P1";
23"PVDDIO_P1_EN";
24"CPU0_PWR_GOOD";
25"FM_PLD_OCP_SFF_PWR_GOOD";
26"PVDD18_S5_P0_EN";
27"FM_PVDD11_S3_P1_EN";
28"PWRGD_PVDD18_S5_R_P1";
29"CPU1_FORCE_SELFREFRESH";
30"FM_FORCE_ALL_PWRON";
31"FM_CLK_BUFFER_EN";
32"CPU0_FORCE_SELFREFRESH";
33"CPU1_PWR_GD_IN";
34"FM_CPU1_PWR_GD_IN";
35"FM_CPU0_FORCE_SELFREFRESH";
36"FM_CLK_BUFFER_EN_R";
37"FM_FORCE_ALL_PWRON_R";
38"FM_CPU1_FORCE_SELFREFRESH";
39"SCM_IRQ_1V8_R_N";
40"WC_PRSNT_0_N";
41"P12V_ALL_PWROK_R";
42"WC_PRSNT_2_N";
43"FM_ROM_LS_EN";
44"CPU1_PWRGD_OUT";
45"FM_ROM_SD_LS_OE";
46"BMC_JTAG_SEL_R";
47"FM_PLD_CPU0_PRSNT_HDT"CDS_PHYS_NET_NAME"FM_PLD_CPU0_PRSNT_HDT";
48"FM_CPU1_PWRGD_OUT";
49"PWRGD_P12V_FAN_SR_R";
50"FM_PVDD33_S5_EN";
51"FM_LED_D0";
52"PRSNT1_SLOT2_R_N";
53"PRSNT1_SLOT1_R_N";
54"FM_PWRGD_PVDD11_S3_P1";
55"CPU0_HDT_BYPASS_SEL";
56"CPU1_JTAG_BUF_R_OE";
57"FM_SPD_CPU0_SWITCH_CTRL_R_N";
58"SW_P12V_FAN_DR_EN";
59"FM_LED_D4";
60"FM_LED_D7";
61"RST_PERST_M2_2_N";
62"RST_PERST_OCP_SFF_N";
63"PRSNT_HDT_N";
64"SPI_PLD_CS_N"CDS_PHYS_NET_NAME"SPI_PLD_CS_N";
65"SPI_PLD_D0"CDS_PHYS_NET_NAME"SPI_PLD_D0";
66"P12V_E1S_2_EN";
67"P12V_E1S_1_EN";
68"PWGD_P3V3_E1S_1";
69"FM_E1S_2_R_PWRDIS";
70"BMC_HPM_FPGA_LED1";
71"FM_E1S_2_PWRDIS";
72"FM_PWRGD_PVDDCR_CPU0_P1";
73"PVDDCR_CPU0_P0_PMALERT";
74"PRSNT1_SLOT1_N";
75"FM_SPD_CPU0_SWITCH_CTRL_N";
76"FM_FAN_DR_FULL_SPEED";
77"FM_FAN_SR_FULL_SPEED";
78"CHASSIS_LEAK2_BUF_R";
79"HSC_GPIO2_PLD_N";
80"PMDU_NODE_ID0";
81"HSC_GPIO1_PLD_N";
82"PRSNT_OCP_N";
83"P3V3_E1S_1_EN";
84"FM_E1S_1_R_PWRDIS";
85"SW_P12V_FAN_SR_EN";
86"PWGD_P3V3_E1S_3";
87"P12V_E1S_3_PWRGD";
88"FM_UART_LS_EN";
89"FM_CPU0_NMI_SYNC_FLOOD_N";
90"FM_CPU0_PWR_BTN_N";
91"FM_P1_PCC1_R_N";
92"FM_FAN_DR_FAIL_N";
93"FM_FAN_SR_FAIL_N";
94"FM_P0_PCC1_R_N";
95"FM_P0_PCC0_R_N";
96"APML_CPU1_ALERT_R_N";
97"APML_CPU0_ALERT_R_N";
98"CPU1_SPD_HOST_CTRL_R1_N";
99"P12V_E1S_2_EN_R";
100"FM_E1S_1_PWRDIS";
101"P3V3_E1S_1_EN_R";
102"SLOT2_SKU_ID1";
103"FM_PWRGD_PVDDIO_P0";
104"SCM_USB_OC_R_N";
105"FM_LED_D5";
106"SW_P3V3_EN";
107"RST_PERST_E1S_1_R_N";
108"FM_RST_PERST_SCM_R_N";
109"PRSNT2_SLOT2_R_N";
110"PSU1_PS_ON_R_N";
111"PRSNT2_SLOT1_R_N";
112"P3V3_E1S_2_EN";
113"FM_PVDDCR_CPU0_P1_R_EN";
114"FM_PWRGD_PVDD11_S3_P0";
115"FM_PVDDIO_P0_EN";
116"P12V_E1S_1_EN_R";
117"FM_PLD_CPU1_PRSNT_HDT"CDS_PHYS_NET_NAME"FM_PLD_CPU1_PRSNT_HDT";
118"BMC_JTAG_SEL";
119"ROM_SD_LS_OE";
120"ROM_LS_EN";
121"CPU0_SPD_HOST_CTRL_N";
122"CPU1_HDT_BYPASS_SEL";
123"P12V_ALL_PWROK";
124"SCM_IRQ_1V8_N";
125"CPU1_JTAG_BUF_OE";
126"FM_CPU1_NMI_SYNC_FLOOD_N";
127"SCM_USB_OC_N";
128"FM_BIOS_USB_RECOVERY";
129"ESPI_CPU0_CS1_N";
130"ESPI_CPU0_ALERT_N";
131"RST_ESPI_CPU0_RSTOUT_N";
132"ESPI_CPU0_D0";
133"ESPI_CPU0_D1";
134"ESPI_CPU0_D2";
135"SMB_SLOT1_ALERT_R_N";
136"SLOT2_CLKREQ_1_R_N";
137"FM_CPU0_NV_SAVE_N";
138"FM_CPU1_SYS_RESET_N";
139"FM_CPU0_SYS_RESET_N";
140"SLOT1_CLKREQ_0_R_N";
141"FM_CPU0_RSMRST_N";
142"SLOT1_CLKREQ_1_R_N";
143"RST_CPU1_PERST0_R_N";
144"CHASSIS_LEAK1_BUF_R";
145"CHASSIS_LEAK0_BUF_R";
146"RST_CPU0_PERST1_R_N";
147"SMB_SLOT2_ALERT_R_N";
148"SLOT2_CLKREQ_0_R_N";
149"RST_CPU0_KBRST_N";
150"FM_CPU1_SLP_S3_N";
151"FM_CPU1_SLP_S5_N";
152"RST_CPU1_PERST1_R_N";
153"RST_CPU0_PERST0_R_N";
154"FM_CPU0_SLP_S3_N";
155"FM_CPU1_RSMRST_N";
156"FM_RST_CPU0_RESETL_N";
157"FM_RST_CPU1_RESETL_N";
158"RST_ESPI_CPU0_RSTOUT_R_N";
159"P12V_SCM_PWRGD";
160"WC_PRSNT_1_N";
161"CPU0_SPD_HOST_CTRL_R1_N";
162"RST_PERST_E1S_4_N";
163"RST_PERST_SLOT2_0_N";
164"RST_PERST_M2_1_N";
165"RST_SMBMUX_U7_R_N";
166"RST_PERST_SLOT2_0_R_N";
167"FM_LED_D6";
168"PVDD33_S5_EN";
169"CLK_ESPI_CPU0_CLK1";
170"FM_CPU0_HDT_CONN_TESTEN";
171"PWRGD_P12V_FAN_DR_R";
172"PWRGD_P12V_MEM_R";
173"FM_JTAG_BMC_OE";
174"CPU0_HDT_CONN_TESTEN";
175"CLK_ESPI_CPU0_R1_CLK1";
176"ESPI_CPU0_CS1_R_N";
177"ESPI_CPU0_ALERT_R_N";
178"CPU1_SMERR_N";
179"SMB_CPU_5_R1_SCL";
180"SMB_CPU_5_R1_SDA";
181"FM_BIOS_POST_CMPLT_BUF_R_N";
182"ESPI_CPU0_R1_D0";
183"FM_CPU1_SMERR_N";
184"FM_SMERR_LED_R_N";
185"FM_CPU0_SMERR_N";
186"PWRGD_P3V3_R";
187"PWRGD_P12V_R";
188"CPU0_JTAG_BUF_R_OE";
189"FM_PWRGD_CPU0_PWROK";
190"PVDD11_S3_P0_RESET_N";
191"CPU1_NMI_SYNC_FLOOD_N";
192"FM_BIOS_POST_CMPLT_BUF_N";
193"HDT_HDR_RESET_N";
194"HDT_HDR_PWROK";
195"ESPI_CPU0_D3";
196"FM_LED_D1";
197"FM_PWRGD_PVDDCR_CPU1_P1";
198"PWRGD_PVDD11_S3_P0";
199"PVDDCR_CPU0_P1_EN";
200"UART_LS_EN";
201"PWRGD_PVDDCR_CPU1_P1";
202"PWRGD_PVDDCR_CPU0_P1";
203"PWRGD_PVDDIO_P0";
204"PRSNT1_SLOT2_N";
205"PVDDIO_P0_EN";
206"FM_CPU0_SLP_S5_N";
207"BIOS_DEBUG_MODE_R";
208"FM_HDT_HDR_RESET_N";
209"ESPI_CPU0_R1_D1";
210"ESPI_CPU0_R1_D2";
211"ESPI_CPU0_R1_D3";
212"FM_HDT_HDR_PWROK";
213"RST_CPU1_RESETL_N";
214"CPU0_CLK_STRAP_SEL";
215"CPU0_NMI_SYNC_FLOOD_N";
216"PVDD11_S3_P1_RESET_N";
217"CPU1_NV_SAVE_N";
218"PWRGD_CPU0_PWROK";
219"RST_CPU0_KBRST_R_N";
220"CPU0_JTAG_BUF_OE";
221"CPU0_NV_SAVE_N";
222"RST_CPU1_SYS_N";
223"RST_CPU0_SYS_N";
224"RST_CPU0_RSMRST_N";
225"RST_CPU1_RSMRST_N";
226"FM_CPU1_NV_SAVE_N";
227"BIOS_DEBUG_MODE";
228"FM_P1_PCC0_R_N";
229"FM_PWRGD_CPU1_PWROK";
230"FM_CPU0_CLK_STRAP_SEL";
231"CPU0_SMERR_N";
232"FM_SMERR_LED_N";
233"RST_CPU1_PERST0_N";
234"RST_CPU0_RESETL_N";
235"RST_CPU1_PERST1_N";
236"RST_CPU0_PERST1_N";
237"FM_P1_PCC0_N";
238"PWRGD_CPU1_PWROK";
239"RST_CPU0_PERST0_N";
240"FM_P0_PCC1_N";
241"CPU0_PWR_BTN_N";
242"CPU1_SPD_HOST_CTRL_N";
243"FM_P1_PCC1_N";
244"RST_PERST_SLOT1_1_R_N";
245"SW_P12V_MEM_EN";
246"RST_PERST_SLOT1_1_N";
247"P12V_E1S_4_EN_R";
248"PRSNT2_SLOT2_N";
249"FM_RST_PERST_SCM_N";
250"RST_PERST_E1S_1_N";
251"P12V_E1S_3_EN_R";
252"P3V3_E1S_2_EN_R";
253"PSU1_PS_ON_N";
254"PRSNT2_SLOT1_N";
255"RST_PERST_E1S_3_N";
256"RST_PERST_E1S_3_R_N";
257"P12V_E1S_4_EN";
258"P12V_E1S_3_EN";
259"RST_PERST_SLOT3_R_N";
260"FM_FPGA_SR_FAN_PWM_SEL";
261"RST_PERST_M2_2_R_N";
262"RST_PERST_M2_1_R_N";
263"FM_E1S_4_R_PWRDIS";
264"SW_P12V_EN";
265"RST_PERST_E1S_4_R_N";
266"RST_PERST_SLOT3_N";
267"FPGA_SR_FAN_PWM_SEL";
268"FM_E1S_3_R_PWRDIS";
269"FM_E1S_4_PWRDIS";
270"RST_SMBMUX_U8_N";
271"P3V3_E1S_3_EN_R";
272"P3V3_E1S_4_EN_R";
273"P12V_E1S_4_PWRGD";
274"PWGD_P3V3_E1S_4";
275"FM_E1S_3_PWRDIS";
276"RST_SMBMUX_U7_N";
277"RST_PERST_E1S_2_N";
278"RST_SMBMUX_U8_R_N";
279"RST_PERST_E1S_2_R_N";
280"FM_P0_PCC0_N";
281"RST_PERST_SLOT1_0_R_N";
282"RST_PERST_SLOT2_1_R_N";
283"FM_FPGA_DR_FAN_PWM_SEL";
284"P3V3_E1S_4_EN";
285"P3V3_E1S_3_EN";
286"FPGA_DR_FAN_PWM_SEL";
287"RST_PERST_SLOT1_0_N";
288"RST_PERST_SLOT2_1_N";
%"Q_RES"
"1","(-3150,6000)","0","pure_quanta","I1897";
;
LOCATION"R933"
$SEC"1"
CDS_SEC"1"
VALUE"33"
ROOM"RST_CPU0_PLD_TO_DIMM"
PACK_TYPE"0402LF"
PART_NUMBER"CS03302JB29"
TOLERANCE"5%"
MATERIAL"CHIP"
WATTAGE"1/16W"
BOM_COST"MEM"
CDS_LIB"pure_quanta";
"B"
$PN"2"232;
"A"
$PN"1"184;
%"Q_RES"
"1","(-3150,5950)","0","pure_quanta","I1898";
;
LOCATION"R250"
$SEC"1"
CDS_SEC"1"
VALUE"0"
ROOM"RST_CPU0_PLD_TO_DIMM"
PACK_TYPE"0402LF"
PART_NUMBER"CS00002JB38"
TOLERANCE"5%"
MATERIAL"CHIP"
WATTAGE"1/16W"
BOM_COST"MEM"
CDS_LIB"pure_quanta";
"B"
$PN"2"231;
"A"
$PN"1"185;
%"Q_RES"
"1","(-3150,5750)","0","pure_quanta","I1899";
;
LOCATION"R193"
$SEC"1"
CDS_SEC"1"
VALUE"0"
ROOM"RST_CPU0_PLD_TO_DIMM"
PACK_TYPE"0402LF"
PART_NUMBER"CS00002JB38"
TOLERANCE"5%"
MATERIAL"CHIP"
WATTAGE"1/16W"
BOM_COST"MEM"
CDS_LIB"pure_quanta";
"B"
$PN"2"178;
"A"
$PN"1"183;
%"Q_RES"
"1","(-3150,5550)","0","pure_quanta","I1913";
;
LOCATION"R258"
$SEC"1"
CDS_SEC"1"
VALUE"0"
ROOM"RST_CPU0_PLD_TO_DIMM"
PACK_TYPE"0402LF"
PART_NUMBER"CS00002JB38"
TOLERANCE"5%"
MATERIAL"CHIP"
WATTAGE"1/16W"
BOM_COST"MEM"
CDS_LIB"pure_quanta";
"B"
$PN"2"174;
"A"
$PN"1"170;
%"Q_RES"
"1","(-3150,5600)","0","pure_quanta","I1914";
;
LOCATION"R1203"
$SEC"1"
CDS_SEC"1"
VALUE"33"
CDS_LIB"pure_quanta"
BOM_COST"MEM"
WATTAGE"1/16W"
MATERIAL"CHIP"
TOLERANCE"5%"
PART_NUMBER"CS03302JB29"
PACK_TYPE"0402LF"
ROOM"RST_CPU0_PLD_TO_DIMM";
"B"
$PN"2"227;
"A"
$PN"1"207;
%"Q_RES"
"1","(-3150,4750)","0","pure_quanta","I1920";
;
LOCATION"R277"
$SEC"1"
CDS_SEC"1"
VALUE"33"
ROOM"RST_CPU0_PLD_TO_DIMM"
PACK_TYPE"0402LF"
PART_NUMBER"CS03302JB29"
TOLERANCE"5%"
MATERIAL"CHIP"
WATTAGE"1/16W"
CDS_LIB"pure_quanta"
BOM_COST"MEM";
"B"
$PN"2"191;
"A"
$PN"1"126;
%"Q_RES"
"1","(-6350,5900)","0","pure_quanta","I1921";
;
LOCATION"R254"
$SEC"1"
CDS_SEC"1"
VALUE"0"
ROOM"RST_CPU0_PLD_TO_DIMM"
PACK_TYPE"0402LF"
PART_NUMBER"CS00002JB38"
TOLERANCE"5%"
MATERIAL"CHIP"
WATTAGE"1/16W"
BOM_COST"MEM"
CDS_LIB"pure_quanta";
"B"
$PN"2"153;
"A"
$PN"1"239;
%"Q_RES"
"1","(-6350,5850)","0","pure_quanta","I1922";
;
LOCATION"R198"
$SEC"1"
CDS_SEC"1"
VALUE"0"
ROOM"RST_CPU0_PLD_TO_DIMM"
PACK_TYPE"0402LF"
PART_NUMBER"CS00002JB38"
TOLERANCE"5%"
MATERIAL"CHIP"
WATTAGE"1/16W"
BOM_COST"MEM"
CDS_LIB"pure_quanta";
"B"
$PN"2"152;
"A"
$PN"1"235;
%"Q_RES"
"1","(-6350,5500)","0","pure_quanta","I1923";
;
LOCATION"R197"
$SEC"1"
CDS_SEC"1"
VALUE"0"
ROOM"RST_CPU0_PLD_TO_DIMM"
PACK_TYPE"0402LF"
PART_NUMBER"CS00002JB38"
TOLERANCE"5%"
MATERIAL"CHIP"
WATTAGE"1/16W"
BOM_COST"MEM"
CDS_LIB"pure_quanta";
"B"
$PN"2"143;
"A"
$PN"1"233;
%"Q_RES"
"1","(-6350,5650)","0","pure_quanta","I1924";
;
LOCATION"R255"
$SEC"1"
CDS_SEC"1"
VALUE"0"
ROOM"RST_CPU0_PLD_TO_DIMM"
PACK_TYPE"0402LF"
PART_NUMBER"CS00002JB38"
TOLERANCE"5%"
MATERIAL"CHIP"
WATTAGE"1/16W"
BOM_COST"MEM"
CDS_LIB"pure_quanta";
"B"
$PN"2"146;
"A"
$PN"1"236;
%"Q_RES"
"1","(-6350,5400)","0","pure_quanta","I1925";
;
LOCATION"R273"
$SEC"1"
CDS_SEC"1"
VALUE"33"
ROOM"RST_CPU0_PLD_TO_DIMM"
PACK_TYPE"0402LF"
PART_NUMBER"CS03302JB29"
TOLERANCE"5%"
MATERIAL"CHIP"
WATTAGE"1/16W"
CDS_LIB"pure_quanta"
BOM_COST"MEM";
"B"
$PN"2"155;
"A"
$PN"1"225;
%"Q_RES"
"1","(-6350,5350)","0","pure_quanta","I1926";
;
LOCATION"R217"
$SEC"1"
CDS_SEC"1"
VALUE"33"
ROOM"RST_CPU0_PLD_TO_DIMM"
PACK_TYPE"0402LF"
PART_NUMBER"CS03302JB29"
TOLERANCE"5%"
MATERIAL"CHIP"
WATTAGE"1/16W"
CDS_LIB"pure_quanta"
BOM_COST"MEM";
"B"
$PN"2"141;
"A"
$PN"1"224;
%"Q_RES"
"1","(-6350,5250)","0","pure_quanta","I1927";
;
LOCATION"R216"
$SEC"1"
CDS_SEC"1"
VALUE"33"
ROOM"RST_CPU0_PLD_TO_DIMM"
PACK_TYPE"0402LF"
PART_NUMBER"CS03302JB29"
TOLERANCE"5%"
MATERIAL"CHIP"
WATTAGE"1/16W"
CDS_LIB"pure_quanta"
BOM_COST"MEM";
"B"
$PN"2"139;
"A"
$PN"1"223;
%"Q_RES"
"1","(-6350,5150)","0","pure_quanta","I1928";
;
LOCATION"R253"
$SEC"1"
CDS_SEC"1"
VALUE"0"
ROOM"RST_CPU0_PLD_TO_DIMM"
PACK_TYPE"0402LF"
PART_NUMBER"CS00002JB38"
TOLERANCE"5%"
MATERIAL"CHIP"
WATTAGE"1/16W"
CDS_LIB"pure_quanta"
BOM_COST"MEM";
"B"
$PN"2"137;
"A"
$PN"1"221;
%"Q_RES"
"1","(-6350,5200)","0","pure_quanta","I1929";
;
LOCATION"R272"
$SEC"1"
CDS_SEC"1"
MATERIAL"EMPTY"
VALUE"0"
ROOM"RST_CPU0_PLD_TO_DIMM"
PACK_TYPE"0402LF"
PART_NUMBER"CS00002JB38"
TOLERANCE"5%"
WATTAGE"1/16W"
BOM_COST"MEM"
CDS_LIB"pure_quanta";
"B"
$PN"2"138;
"A"
$PN"1"222;
%"Q_RES"
"1","(-6350,5000)","0","pure_quanta","I1930";
;
LOCATION"R241"
$SEC"1"
CDS_SEC"1"
VALUE"0"
ROOM"RST_CPU0_PLD_TO_DIMM"
PACK_TYPE"0402LF"
PART_NUMBER"CS00002JB38"
TOLERANCE"5%"
MATERIAL"CHIP"
WATTAGE"1/16W"
CDS_LIB"pure_quanta"
BOM_COST"MEM";
"B"
$PN"2"156;
"A"
$PN"1"234;
%"Q_RES"
"1","(-6350,4950)","0","pure_quanta","I1931";
;
LOCATION"R57"
$SEC"1"
CDS_SEC"1"
VALUE"0"
ROOM"RST_CPU0_PLD_TO_DIMM"
PACK_TYPE"0402LF"
PART_NUMBER"CS00002JB38"
TOLERANCE"5%"
MATERIAL"CHIP"
WATTAGE"1/16W"
BOM_COST"MEM"
CDS_LIB"pure_quanta";
"B"
$PN"2"157;
"A"
$PN"1"213;
%"Q_RES"
"1","(-6350,4900)","0","pure_quanta","I1932";
;
LOCATION"R463"
$SEC"1"
CDS_SEC"1"
VALUE"33"
CDS_LIB"pure_quanta"
WATTAGE"1/16W"
MATERIAL"CHIP"
TOLERANCE"5%"
PART_NUMBER"CS03302JB29"
PACK_TYPE"0402LF";
"B"
$PN"2"149;
"A"
$PN"1"219;
%"Q_RES"
"1","(-6350,4750)","0","pure_quanta","I1934";
;
LOCATION"R196"
$SEC"1"
CDS_SEC"1"
VALUE"0"
ROOM"RST_CPU0_PLD_TO_DIMM"
PACK_TYPE"0402LF"
PART_NUMBER"CS00002JB38"
TOLERANCE"5%"
MATERIAL"CHIP"
WATTAGE"1/16W"
BOM_COST"MEM"
CDS_LIB"pure_quanta";
"B"
$PN"2"226;
"A"
$PN"1"217;
%"Q_RES"
"1","(-6350,4800)","0","pure_quanta","I1935";
;
LOCATION"R242"
$SEC"1"
CDS_SEC"1"
VALUE"0"
ROOM"RST_CPU0_PLD_TO_DIMM"
PACK_TYPE"0402LF"
PART_NUMBER"CS00002JB38"
TOLERANCE"5%"
MATERIAL"CHIP"
WATTAGE"1/16W"
CDS_LIB"pure_quanta"
BOM_COST"MEM";
"B"
$PN"2"189;
"A"
$PN"1"218;
%"Q_RES"
"1","(-3150,4650)","0","pure_quanta","I1951";
;
LOCATION"R588"
$SEC"1"
CDS_SEC"1"
VALUE"33"
ROOM"RST_CPU0_PLD_TO_DIMM"
PACK_TYPE"0402LF"
PART_NUMBER"CS03302JB29"
TOLERANCE"5%"
MATERIAL"CHIP"
WATTAGE"1/16W"
BOM_COST"MEM"
CDS_LIB"pure_quanta";
"B"
$PN"2"127;
"A"
$PN"1"104;
%"Q_RES"
"1","(-3150,4550)","0","pure_quanta","I1952";
;
LOCATION"R251"
$SEC"1"
CDS_SEC"1"
VALUE"0"
ROOM"RST_CPU0_PLD_TO_DIMM"
PACK_TYPE"0402LF"
PART_NUMBER"CS00002JB38"
TOLERANCE"5%"
MATERIAL"CHIP"
WATTAGE"1/16W"
BOM_COST"MEM"
CDS_LIB"pure_quanta";
"B"
$PN"2"121;
"A"
$PN"1"161;
%"Q_RES"
"1","(-3150,4500)","0","pure_quanta","I1953";
;
LOCATION"R173"
$SEC"1"
CDS_SEC"1"
VALUE"33"
ROOM"RST_CPU0_PLD_TO_DIMM"
PACK_TYPE"0402LF"
PART_NUMBER"CS03302JB29"
TOLERANCE"5%"
MATERIAL"CHIP"
WATTAGE"1/16W"
CDS_LIB"pure_quanta"
BOM_COST"MEM";
"B"
$PN"2"122;
"A"
$PN"1"117;
%"Q_RES"
"1","(-3150,4450)","0","pure_quanta","I1954";
;
LOCATION"R161"
$SEC"1"
CDS_SEC"1"
VALUE"33"
ROOM"RST_CPU0_PLD_TO_DIMM"
PACK_TYPE"0402LF"
PART_NUMBER"CS03302JB29"
TOLERANCE"5%"
MATERIAL"CHIP"
WATTAGE"1/16W"
BOM_COST"MEM"
CDS_LIB"pure_quanta";
"B"
$PN"2"125;
"A"
$PN"1"56;
%"Q_RES"
"1","(-3150,4400)","0","pure_quanta","I1955";
;
LOCATION"R174"
$SEC"1"
CDS_SEC"1"
VALUE"33"
ROOM"RST_CPU0_PLD_TO_DIMM"
PACK_TYPE"0402LF"
PART_NUMBER"CS03302JB29"
TOLERANCE"5%"
MATERIAL"CHIP"
WATTAGE"1/16W"
BOM_COST"MEM"
CDS_LIB"pure_quanta";
"B"
$PN"2"124;
"A"
$PN"1"39;
%"Q_RES"
"1","(-3150,4300)","0","pure_quanta","I1956";
;
LOCATION"R372"
$SEC"1"
CDS_SEC"1"
VALUE"33"
CDS_LIB"pure_quanta"
BOM_COST"MEM"
WATTAGE"1/16W"
MATERIAL"CHIP"
TOLERANCE"5%"
PART_NUMBER"CS03302JB29"
PACK_TYPE"0402LF"
ROOM"RST_CPU0_PLD_TO_DIMM";
"B"
$PN"2"123;
"A"
$PN"1"41;
%"Q_RES"
"1","(-3150,4200)","0","pure_quanta","I1957";
;
LOCATION"R1359"
$SEC"1"
CDS_SEC"1"
VALUE"0"
ROOM"RST_CPU0_PLD_TO_DIMM"
PACK_TYPE"0402LF"
PART_NUMBER"CS00002JB38"
TOLERANCE"5%"
MATERIAL"CHIP"
WATTAGE"1/16W"
CDS_LIB"pure_quanta"
BOM_COST"MEM";
"B"
$PN"2"118;
"A"
$PN"1"46;
%"Q_RES"
"1","(-3150,4050)","0","pure_quanta","I1958";
;
LOCATION"R395"
$SEC"1"
CDS_SEC"1"
VALUE"0"
CDS_LIB"pure_quanta"
BOM_COST"MEM"
WATTAGE"1/16W"
MATERIAL"CHIP"
TOLERANCE"5%"
PART_NUMBER"CS00002JB38"
PACK_TYPE"0402LF"
ROOM"RST_CPU0_PLD_TO_DIMM";
"B"
$PN"2"75;
"A"
$PN"1"57;
%"Q_RES"
"1","(-3150,4000)","0","pure_quanta","I1959";
;
LOCATION"R158"
$SEC"1"
CDS_SEC"1"
VALUE"33"
ROOM"RST_CPU0_PLD_TO_DIMM"
PACK_TYPE"0402LF"
PART_NUMBER"CS03302JB29"
TOLERANCE"5%"
MATERIAL"CHIP"
WATTAGE"1/16W"
BOM_COST"MEM"
CDS_LIB"pure_quanta";
"B"
$PN"2"55;
"A"
$PN"1"47;
%"Q_RES"
"1","(-3150,3850)","0","pure_quanta","I1960";
;
LOCATION"R186"
$SEC"1"
CDS_SEC"1"
VALUE"33"
ROOM"RST_CPU0_PLD_TO_DIMM"
PACK_TYPE"0402LF"
PART_NUMBER"CS03302JB29"
TOLERANCE"5%"
MATERIAL"CHIP"
WATTAGE"1/16W"
BOM_COST"MEM"
CDS_LIB"pure_quanta";
"B"
$PN"2"32;
"A"
$PN"1"35;
%"Q_RES"
"1","(-3150,3800)","0","pure_quanta","I1961";
;
LOCATION"R407"
$SEC"1"
CDS_SEC"1"
VALUE"33"
ROOM"RST_CPU0_PLD_TO_DIMM"
PACK_TYPE"0402LF"
PART_NUMBER"CS03302JB29"
TOLERANCE"5%"
MATERIAL"CHIP"
WATTAGE"1/16W"
BOM_COST"MEM"
CDS_LIB"pure_quanta";
"B"
$PN"2"31;
"A"
$PN"1"36;
%"Q_RES"
"1","(-3150,3700)","0","pure_quanta","I1962";
;
LOCATION"R1202"
$SEC"1"
CDS_SEC"1"
VALUE"0"
ROOM"RST_CPU0_PLD_TO_DIMM"
PACK_TYPE"0402LF"
PART_NUMBER"CS00002JB38"
TOLERANCE"5%"
MATERIAL"CHIP"
WATTAGE"1/16W"
BOM_COST"MEM"
CDS_LIB"pure_quanta";
"B"
$PN"2"30;
"A"
$PN"1"37;
%"Q_RES"
"1","(-3150,3650)","0","pure_quanta","I1964";
;
LOCATION"R265"
$SEC"1"
CDS_SEC"1"
VALUE"33"
ROOM"RST_CPU0_PLD_TO_DIMM"
PACK_TYPE"0402LF"
PART_NUMBER"CS03302JB29"
TOLERANCE"5%"
MATERIAL"CHIP"
WATTAGE"1/16W"
BOM_COST"MEM"
CDS_LIB"pure_quanta";
"B"
$PN"2"29;
"A"
$PN"1"38;
%"LCMXO3D9400HC5BG484C"
"7","(-4750,4825)","0","pure_quanta","I1965";
;
LOCATION"U18"
$SEC"7"
CDS_SEC"7"
PART_NUMBER"AJ094000T05"
VALUE"LCMXO3D-9400HC-5BG484C"
MATERIAL"IC"
PART_TYPE"SMLF"
CDS_LIB"pure_quanta"
CDS_LMAN_SYM_OUTLINE"-500,1275,500,-1275"
NEEDS_NO_SIZE"TRUE";
"PR30D"
$PN"Y20"0;
"PR30C"
$PN"W19"38;
"PR28D"
$PN"U18"47;
"PR28C"
$PN"U19"57;
"PR28B"
$PN"W21"45;
"PR28A"
$PN"Y22"43;
"PR27D"
$PN"U20"46;
"PR27C"
$PN"T17"42;
"PR27B"
$PN"T18"41;
"PR27A"
$PN"T19"40;
"PR26D"
$PN"T20"39;
"PR26C"
$PN"R16"56;
"PR26B"
$PN"R17"117;
"PR26A"
$PN"R18"161;
"PR25D"
$PN"R19"104;
"PR25C"
$PN"R20"160;
"PR24D"
$PN"U21"181;
"PR24C"
$PN"U22"208;
"PR24B"
$PN"P16"212;
"PR24A"
$PN"P17"211;
"PR21D"
$PN"P18"210;
"PR21C"
$PN"P19"209;
"PR21B"
$PN"T21"182;
"PR21A"
$PN"T22"158;
"PR20D"
$PN"P20"177;
"PR20C"
$PN"P22"176;
"PR19D"
$PN"N19"172;
"PR19C"
$PN"N20"171;
"PR18D"
$PN"N18"187;
"PR18C"
$PN"N17"159;
"PR18B"
$PN"N16"183;
"PR18A"
$PN"M16"186;
"PR17D"
$PN"M19"180;
"PR17C"
$PN"M20"179;
"PR16D"
$PN"M17"49;
"PR16C"
$PN"L22"76;
"PR14D"
$PN"L20"79;
"PR14C"
$PN"L19"81;
"PR13D"
$PN"K16"96;
"PR13C"
$PN"K17"95;
"PR13B"
$PN"K18"94;
"PR13A"
$PN"K19"93;
"PR12D"
$PN"K20"92;
"PR12C"
$PN"J20"91;
"PR12B"
$PN"J22"90;
"PR12A"
$PN"J21"148;
"PR11D"
$PN"J19"228;
"PR11C"
$PN"J18"229;
"PR11B"
$PN"J17"230;
"PR11A"
$PN"J16"89;
"PR10D"
$PN"H16"216;
"PR10C"
$PN"H17"190;
"PR10B"
$PN"H18"226;
"PR10A"
$PN"H19"189;
"PR7D"
$PN"H20"188;
"PR7C"
$PN"G17"149;
"PR6D"
$PN"G18"135;
"PR6C"
$PN"G19"136;
"PR6B"
$PN"G20"137;
"PR6A"
$PN"G21"138;
"PR5D"
$PN"F19"139;
"PR5C"
$PN"F18"140;
"PR5B"
$PN"G22"141;
"PR5A"
$PN"F22"155;
"PR4B"
$PN"E21"144;
"PR4A"
$PN"E22"145;
"PR4D"
$PN"E20"142;
"PR4C"
$PN"E19"143;
"PR3D"
$PN"D20"146;
"PR3C"
$PN"D19"147;
"PR2D"
$PN"G16"152;
"PR2C"
$PN"F17"153;
"PR2A||R_GPLLT_FB"
$PN"C21"206;
"PR2B||R_GPLLC_FB"
$PN"C22"154;
"PR3A||R_GPLLT_IN"
$PN"D22"151;
"PR3B||R_GPLLC_IN"
$PN"D21"150;
"PR7A"
$PN"H22"156;
"PR7B"
$PN"H21"157;
"PR14A"
$PN"L17"97;
"PR14B"
$PN"L16"98;
"PR16A"
$PN"K22"78;
"PR16B"
$PN"L21"77;
"PR17A||PCLKT1_0"
$PN"M22"184;
"PR17B||PCLKC1_0"
$PN"M21"185;
"PR19A"
$PN"N22"207;
"PR19B"
$PN"P21"170;
"PR20A"
$PN"R22"173;
"PR20B"
$PN"R21"175;
"PR25A"
$PN"V22"128;
"PR25B"
$PN"W22"126;
"PR29A"
$PN"AA22"48;
"PR29C"
$PN"U17"35;
"PR29B"
$PN"Y21"34;
"PR29D"
$PN"V19"36;
"PR30A"
$PN"V18"0;
"PR30B"
$PN"W20"37;
%"Q_RES"
"1","(-6350,4600)","0","pure_quanta","I1966";
;
LOCATION"R219"
$SEC"1"
CDS_SEC"1"
VALUE"33"
ROOM"RST_CPU0_PLD_TO_DIMM"
PACK_TYPE"0402LF"
PART_NUMBER"CS03302JB29"
TOLERANCE"5%"
MATERIAL"CHIP"
WATTAGE"1/16W"
BOM_COST"MEM"
CDS_LIB"pure_quanta";
"B"
$PN"2"89;
"A"
$PN"1"215;
%"Q_RES"
"1","(-6350,4500)","0","pure_quanta","I1967";
;
LOCATION"R203"
$SEC"1"
CDS_SEC"1"
VALUE"0"
ROOM"RST_CPU0_PLD_TO_DIMM"
PACK_TYPE"0402LF"
PART_NUMBER"CS00002JB38"
TOLERANCE"5%"
MATERIAL"CHIP"
WATTAGE"1/16W"
CDS_LIB"pure_quanta"
BOM_COST"MEM";
"B"
$PN"2"229;
"A"
$PN"1"238;
%"Q_RES"
"1","(-6350,4550)","0","pure_quanta","I1968";
;
LOCATION"R371"
$SEC"1"
CDS_SEC"1"
VALUE"33"
ROOM"RST_CPU0_PLD_TO_DIMM"
PACK_TYPE"0402LF"
PART_NUMBER"CS03302JB29"
TOLERANCE"5%"
MATERIAL"CHIP"
WATTAGE"1/16W"
BOM_COST"MEM"
CDS_LIB"pure_quanta";
"B"
$PN"2"230;
"A"
$PN"1"214;
%"Q_RES"
"1","(-6350,4450)","0","pure_quanta","I1969";
;
LOCATION"R1278"
$SEC"1"
CDS_SEC"1"
VALUE"33"
ROOM"RST_CPU0_PLD_TO_DIMM"
PACK_TYPE"0402LF"
PART_NUMBER"CS03302JB29"
TOLERANCE"5%"
MATERIAL"CHIP"
WATTAGE"1/16W"
BOM_COST"MEM"
CDS_LIB"pure_quanta";
"B"
$PN"2"228;
"A"
$PN"1"237;
%"Q_RES"
"1","(-6350,4350)","0","pure_quanta","I1970";
;
LOCATION"R215"
$SEC"1"
CDS_SEC"1"
VALUE"33"
ROOM"RST_CPU0_PLD_TO_DIMM"
PACK_TYPE"0402LF"
PART_NUMBER"CS03302JB29"
TOLERANCE"5%"
MATERIAL"CHIP"
WATTAGE"1/16W"
BOM_COST"MEM"
CDS_LIB"pure_quanta";
"B"
$PN"2"90;
"A"
$PN"1"241;
%"Q_RES"
"1","(-6350,4300)","0","pure_quanta","I1971";
;
LOCATION"R1279"
$SEC"1"
CDS_SEC"1"
VALUE"33"
ROOM"RST_CPU0_PLD_TO_DIMM"
PACK_TYPE"0402LF"
PART_NUMBER"CS03302JB29"
TOLERANCE"5%"
MATERIAL"CHIP"
WATTAGE"1/16W"
BOM_COST"MEM"
CDS_LIB"pure_quanta";
"B"
$PN"2"91;
"A"
$PN"1"243;
%"Q_RES"
"1","(-6350,4100)","0","pure_quanta","I1972";
;
LOCATION"R1280"
$SEC"1"
CDS_SEC"1"
VALUE"33"
ROOM"RST_CPU0_PLD_TO_DIMM"
PACK_TYPE"0402LF"
PART_NUMBER"CS03302JB29"
TOLERANCE"5%"
MATERIAL"CHIP"
WATTAGE"1/16W"
BOM_COST"MEM"
CDS_LIB"pure_quanta";
"B"
$PN"2"95;
"A"
$PN"1"280;
%"Q_RES"
"1","(-6350,4150)","0","pure_quanta","I1973";
;
LOCATION"R1281"
$SEC"1"
CDS_SEC"1"
VALUE"33"
ROOM"RST_CPU0_PLD_TO_DIMM"
PACK_TYPE"0402LF"
PART_NUMBER"CS03302JB29"
TOLERANCE"5%"
MATERIAL"CHIP"
WATTAGE"1/16W"
BOM_COST"MEM"
CDS_LIB"pure_quanta";
"B"
$PN"2"94;
"A"
$PN"1"240;
%"Q_RES"
"1","(-6350,3950)","0","pure_quanta","I1974";
;
LOCATION"R194"
$SEC"1"
CDS_SEC"1"
VALUE"0"
ROOM"RST_CPU0_PLD_TO_DIMM"
PACK_TYPE"0402LF"
PART_NUMBER"CS00002JB38"
TOLERANCE"5%"
MATERIAL"CHIP"
WATTAGE"1/16W"
BOM_COST"MEM"
CDS_LIB"pure_quanta";
"B"
$PN"2"98;
"A"
$PN"1"242;
%"Q_RES"
"1","(-2550,2700)","0","pure_quanta","I2057";
;
LOCATION"R649"
$SEC"1"
CDS_SEC"1"
VALUE"33"
ROOM"RST_CPU0_PLD_TO_DIMM"
PACK_TYPE"0402LF"
PART_NUMBER"CS03302JB29"
TOLERANCE"5%"
MATERIAL"CHIP"
WATTAGE"1/16W"
CDS_LIB"pure_quanta"
BOM_COST"MEM";
"B"
$PN"2"252;
"A"
$PN"1"112;
%"Q_RES"
"1","(-2550,2750)","0","pure_quanta","I2058";
;
LOCATION"R671"
$SEC"1"
CDS_SEC"1"
VALUE"0"
CDS_LIB"pure_quanta"
BOM_COST"MEM"
WATTAGE"1/16W"
MATERIAL"CHIP"
TOLERANCE"5%"
PART_NUMBER"CS00002JB38"
PACK_TYPE"0402LF"
ROOM"RST_CPU0_PLD_TO_DIMM";
"B"
$PN"2"253;
"A"
$PN"1"110;
%"Q_RES"
"1","(-2550,2550)","0","pure_quanta","I2059";
;
LOCATION"R685"
$SEC"1"
CDS_SEC"1"
VALUE"33"
ROOM"RST_CPU0_PLD_TO_DIMM"
PACK_TYPE"0402LF"
PART_NUMBER"CS03302JB29"
TOLERANCE"5%"
MATERIAL"CHIP"
WATTAGE"1/16W"
CDS_LIB"pure_quanta"
BOM_COST"MEM";
"B"
$PN"2"250;
"A"
$PN"1"107;
%"Q_RES"
"1","(-2550,2600)","0","pure_quanta","I2060";
;
LOCATION"R957"
$SEC"1"
CDS_SEC"1"
VALUE"33"
ROOM"RST_CPU0_PLD_TO_DIMM"
PACK_TYPE"0402LF"
PART_NUMBER"CS03302JB29"
TOLERANCE"5%"
MATERIAL"CHIP"
WATTAGE"1/16W"
BOM_COST"MEM"
CDS_LIB"pure_quanta";
"B"
$PN"2"249;
"A"
$PN"1"108;
%"Q_RES"
"1","(-2550,2500)","0","pure_quanta","I2061";
;
LOCATION"R487"
$SEC"1"
CDS_SEC"1"
VALUE"33"
ROOM"RST_CPU0_PLD_TO_DIMM"
PACK_TYPE"0402LF"
PART_NUMBER"CS03302JB29"
TOLERANCE"5%"
MATERIAL"CHIP"
WATTAGE"1/16W"
CDS_LIB"pure_quanta"
BOM_COST"MEM";
"B"
$PN"2"251;
"A"
$PN"1"258;
%"Q_RES"
"1","(-2550,2450)","0","pure_quanta","I2062";
;
LOCATION"R644"
$SEC"1"
CDS_SEC"1"
VALUE"33"
ROOM"RST_CPU0_PLD_TO_DIMM"
PACK_TYPE"0402LF"
PART_NUMBER"CS03302JB29"
TOLERANCE"5%"
MATERIAL"CHIP"
WATTAGE"1/16W"
CDS_LIB"pure_quanta"
BOM_COST"MEM";
"B"
$PN"2"247;
"A"
$PN"1"257;
%"Q_RES"
"1","(-2550,2350)","0","pure_quanta","I2063";
;
LOCATION"R175"
$SEC"1"
CDS_SEC"1"
VALUE"33"
ROOM"RST_CPU0_PLD_TO_DIMM"
PACK_TYPE"0402LF"
PART_NUMBER"CS03302JB29"
TOLERANCE"5%"
MATERIAL"CHIP"
WATTAGE"1/16W"
CDS_LIB"pure_quanta"
BOM_COST"MEM";
"B"
$PN"2"246;
"A"
$PN"1"244;
%"Q_RES"
"1","(-2550,2300)","0","pure_quanta","I2064";
;
LOCATION"R793"
$SEC"1"
CDS_SEC"1"
VALUE"33"
ROOM"RST_CPU0_PLD_TO_DIMM"
PACK_TYPE"0402LF"
PART_NUMBER"CS03302JB29"
TOLERANCE"5%"
MATERIAL"CHIP"
WATTAGE"1/16W"
BOM_COST"MEM"
CDS_LIB"pure_quanta";
"B"
$PN"2"255;
"A"
$PN"1"256;
%"Q_RES"
"1","(-2550,2250)","0","pure_quanta","I2065";
;
LOCATION"R686"
$SEC"1"
CDS_SEC"1"
VALUE"33"
ROOM"RST_CPU0_PLD_TO_DIMM"
PACK_TYPE"0402LF"
PART_NUMBER"CS03302JB29"
TOLERANCE"5%"
MATERIAL"CHIP"
WATTAGE"1/16W"
BOM_COST"MEM"
CDS_LIB"pure_quanta";
"B"
$PN"2"277;
"A"
$PN"1"279;
%"Q_RES"
"1","(-2550,2200)","0","pure_quanta","I2066";
;
LOCATION"R490"
$SEC"1"
CDS_SEC"1"
VALUE"33"
ROOM"RST_CPU0_PLD_TO_DIMM"
PACK_TYPE"0402LF"
PART_NUMBER"CS03302JB29"
TOLERANCE"5%"
MATERIAL"CHIP"
WATTAGE"1/16W"
CDS_LIB"pure_quanta"
BOM_COST"MEM";
"B"
$PN"2"276;
"A"
$PN"1"165;
%"Q_RES"
"1","(-2550,2150)","0","pure_quanta","I2067";
;
LOCATION"R494"
$SEC"1"
CDS_SEC"1"
VALUE"33"
ROOM"RST_CPU0_PLD_TO_DIMM"
PACK_TYPE"0402LF"
PART_NUMBER"CS03302JB29"
TOLERANCE"5%"
MATERIAL"CHIP"
WATTAGE"1/16W"
CDS_LIB"pure_quanta"
BOM_COST"MEM";
"B"
$PN"2"270;
"A"
$PN"1"278;
%"Q_RES"
"1","(-2550,2100)","0","pure_quanta","I2068";
;
LOCATION"R865"
$SEC"1"
CDS_SEC"1"
VALUE"33"
ROOM"RST_CPU0_PLD_TO_DIMM"
PACK_TYPE"0402LF"
PART_NUMBER"CS03302JB29"
TOLERANCE"5%"
MATERIAL"CHIP"
WATTAGE"1/16W"
CDS_LIB"pure_quanta"
BOM_COST"MEM";
"B"
$PN"2"271;
"A"
$PN"1"285;
%"Q_RES"
"1","(-2550,2050)","0","pure_quanta","I2069";
;
LOCATION"R917"
$SEC"1"
CDS_SEC"1"
VALUE"33"
ROOM"RST_CPU0_PLD_TO_DIMM"
PACK_TYPE"0402LF"
PART_NUMBER"CS03302JB29"
TOLERANCE"5%"
MATERIAL"CHIP"
WATTAGE"1/16W"
BOM_COST"MEM"
CDS_LIB"pure_quanta";
"B"
$PN"2"272;
"A"
$PN"1"284;
%"Q_RES"
"1","(-2550,1900)","0","pure_quanta","I2070";
;
LOCATION"R1064"
$SEC"1"
CDS_SEC"1"
VALUE"33"
ROOM"RST_CPU0_PLD_TO_DIMM"
PACK_TYPE"0402LF"
PART_NUMBER"CS03302JB29"
TOLERANCE"5%"
MATERIAL"CHIP"
WATTAGE"1/16W"
BOM_COST"MEM"
CDS_LIB"pure_quanta";
"B"
$PN"2"275;
"A"
$PN"1"268;
%"Q_RES"
"1","(-2550,1850)","0","pure_quanta","I2071";
;
LOCATION"R1291"
$SEC"1"
CDS_SEC"1"
VALUE"33"
ROOM"RST_CPU0_PLD_TO_DIMM"
PACK_TYPE"0402LF"
PART_NUMBER"CS03302JB29"
TOLERANCE"5%"
MATERIAL"CHIP"
WATTAGE"1/16W"
BOM_COST"MEM"
CDS_LIB"pure_quanta";
"B"
$PN"2"269;
"A"
$PN"1"263;
%"Q_RES"
"1","(-2550,1650)","0","pure_quanta","I2072";
;
LOCATION"R274"
$SEC"1"
CDS_SEC"1"
VALUE"33"
ROOM"RST_CPU0_PLD_TO_DIMM"
PACK_TYPE"0402LF"
PART_NUMBER"CS03302JB29"
TOLERANCE"5%"
MATERIAL"CHIP"
WATTAGE"1/16W"
CDS_LIB"pure_quanta"
BOM_COST"MEM";
"B"
$PN"2"163;
"A"
$PN"1"166;
%"Q_RES"
"1","(-2550,1700)","0","pure_quanta","I2073";
;
LOCATION"R797"
$SEC"1"
CDS_SEC"1"
VALUE"33"
ROOM"RST_CPU0_PLD_TO_DIMM"
PACK_TYPE"0402LF"
PART_NUMBER"CS03302JB29"
TOLERANCE"5%"
MATERIAL"CHIP"
WATTAGE"1/16W"
BOM_COST"MEM"
CDS_LIB"pure_quanta";
"B"
$PN"2"162;
"A"
$PN"1"265;
%"Q_RES"
"1","(-2550,1300)","0","pure_quanta","I2074";
;
LOCATION"R799"
$SEC"1"
CDS_SEC"1"
VALUE"33"
ROOM"RST_CPU0_PLD_TO_DIMM"
PACK_TYPE"0402LF"
PART_NUMBER"CS03302JB29"
TOLERANCE"5%"
MATERIAL"CHIP"
WATTAGE"1/16W"
CDS_LIB"pure_quanta"
BOM_COST"MEM";
"B"
$PN"2"61;
"A"
$PN"1"261;
%"Q_RES"
"1","(-2550,1450)","0","pure_quanta","I2075";
;
LOCATION"R798"
$SEC"1"
CDS_SEC"1"
VALUE"33"
ROOM"RST_CPU0_PLD_TO_DIMM"
PACK_TYPE"0402LF"
PART_NUMBER"CS03302JB29"
TOLERANCE"5%"
MATERIAL"CHIP"
WATTAGE"1/16W"
BOM_COST"MEM"
CDS_LIB"pure_quanta";
"B"
$PN"2"164;
"A"
$PN"1"262;
%"Q_RES"
"1","(-2550,1100)","0","pure_quanta","I2076";
;
LOCATION"R86"
$SEC"1"
CDS_SEC"1"
VALUE"33"
ROOM"RST_CPU0_PLD_TO_DIMM"
PACK_TYPE"0402LF"
PART_NUMBER"CS03302JB29"
TOLERANCE"5%"
MATERIAL"CHIP"
WATTAGE"1/16W"
CDS_LIB"pure_quanta"
BOM_COST"MEM";
"B"
$PN"2"267;
"A"
$PN"1"260;
%"Q_RES"
"1","(-2550,1200)","0","pure_quanta","I2077";
;
LOCATION"R560"
$SEC"1"
CDS_SEC"1"
VALUE"33"
ROOM"RST_CPU0_PLD_TO_DIMM"
PACK_TYPE"0402LF"
PART_NUMBER"CS03302JB29"
TOLERANCE"5%"
MATERIAL"CHIP"
WATTAGE"1/16W"
BOM_COST"MEM"
CDS_LIB"pure_quanta";
"B"
$PN"2"266;
"A"
$PN"1"259;
%"Q_RES"
"1","(-2550,850)","0","pure_quanta","I2078";
;
LOCATION"R162"
$SEC"1"
CDS_SEC"1"
VALUE"33"
ROOM"RST_CPU0_PLD_TO_DIMM"
PACK_TYPE"0402LF"
PART_NUMBER"CS03302JB29"
TOLERANCE"5%"
MATERIAL"CHIP"
WATTAGE"1/16W"
CDS_LIB"pure_quanta"
BOM_COST"MEM";
"B"
$PN"2"287;
"A"
$PN"1"281;
%"Q_RES"
"1","(-2550,900)","0","pure_quanta","I2079";
;
LOCATION"R439"
$SEC"1"
CDS_SEC"1"
VALUE"33"
ROOM"RST_CPU0_PLD_TO_DIMM"
PACK_TYPE"0402LF"
PART_NUMBER"CS03302JB29"
TOLERANCE"5%"
MATERIAL"CHIP"
WATTAGE"1/16W"
BOM_COST"MEM"
CDS_LIB"pure_quanta";
"B"
$PN"2"288;
"A"
$PN"1"282;
%"Q_RES"
"1","(-2550,650)","0","pure_quanta","I2080";
;
LOCATION"R85"
$SEC"1"
CDS_SEC"1"
VALUE"33"
ROOM"RST_CPU0_PLD_TO_DIMM"
PACK_TYPE"0402LF"
PART_NUMBER"CS03302JB29"
TOLERANCE"5%"
MATERIAL"CHIP"
WATTAGE"1/16W"
CDS_LIB"pure_quanta"
BOM_COST"MEM";
"B"
$PN"2"286;
"A"
$PN"1"283;
%"Q_RES"
"1","(-6500,2900)","0","pure_quanta","I2081";
;
LOCATION"R229"
$SEC"1"
CDS_SEC"1"
VALUE"33"
ROOM"RST_CPU0_PLD_TO_DIMM"
PACK_TYPE"0402LF"
PART_NUMBER"CS03302JB29"
TOLERANCE"5%"
MATERIAL"CHIP"
WATTAGE"1/16W"
CDS_LIB"pure_quanta"
BOM_COST"MEM";
"B"
$PN"2"115;
"A"
$PN"1"205;
%"Q_RES"
"1","(-6500,2950)","0","pure_quanta","I2082";
;
LOCATION"R669"
$SEC"1"
CDS_SEC"1"
VALUE"0"
ROOM"RST_CPU0_PLD_TO_DIMM"
PACK_TYPE"0402LF"
PART_NUMBER"CS00002JB38"
TOLERANCE"5%"
MATERIAL"CHIP"
WATTAGE"1/16W"
CDS_LIB"pure_quanta"
BOM_COST"MEM";
"B"
$PN"2"52;
"A"
$PN"1"204;
%"Q_RES"
"1","(-6500,3000)","0","pure_quanta","I2083";
;
LOCATION"R667"
$SEC"1"
CDS_SEC"1"
VALUE"0"
ROOM"RST_CPU0_PLD_TO_DIMM"
PACK_TYPE"0402LF"
PART_NUMBER"CS00002JB38"
TOLERANCE"5%"
MATERIAL"CHIP"
WATTAGE"1/16W"
CDS_LIB"pure_quanta"
BOM_COST"MEM";
"B"
$PN"2"53;
"A"
$PN"1"74;
%"Q_RES"
"1","(-6500,2850)","0","pure_quanta","I2084";
;
LOCATION"R230"
$SEC"1"
CDS_SEC"1"
VALUE"0"
ROOM"RST_CPU0_PLD_TO_DIMM"
PACK_TYPE"0402LF"
PART_NUMBER"CS00002JB38"
TOLERANCE"5%"
MATERIAL"CHIP"
WATTAGE"1/16W"
BOM_COST"MEM"
CDS_LIB"pure_quanta";
"B"
$PN"2"103;
"A"
$PN"1"203;
%"Q_RES"
"1","(-6500,2650)","0","pure_quanta","I2085";
;
LOCATION"R208"
$SEC"1"
CDS_SEC"1"
VALUE"33"
CDS_LIB"pure_quanta"
BOM_COST"MEM"
WATTAGE"1/16W"
MATERIAL"CHIP"
TOLERANCE"5%"
PART_NUMBER"CS03302JB29"
PACK_TYPE"0402LF"
ROOM"RST_CPU0_PLD_TO_DIMM";
"B"
$PN"2"113;
"A"
$PN"1"199;
%"Q_RES"
"1","(-6500,2700)","0","pure_quanta","I2086";
;
LOCATION"R228"
$SEC"1"
CDS_SEC"1"
VALUE"0"
ROOM"RST_CPU0_PLD_TO_DIMM"
PACK_TYPE"0402LF"
PART_NUMBER"CS00002JB38"
TOLERANCE"5%"
MATERIAL"CHIP"
WATTAGE"1/16W"
CDS_LIB"pure_quanta"
BOM_COST"MEM";
"B"
$PN"2"114;
"A"
$PN"1"198;
%"Q_RES"
"1","(-6500,2450)","0","pure_quanta","I2095";
;
LOCATION"R286"
$SEC"1"
CDS_SEC"1"
VALUE"0"
ROOM"RST_CPU0_PLD_TO_DIMM"
PACK_TYPE"0402LF"
PART_NUMBER"CS00002JB38"
TOLERANCE"5%"
MATERIAL"CHIP"
WATTAGE"1/16W"
CDS_LIB"pure_quanta"
BOM_COST"MEM";
"B"
$PN"2"197;
"A"
$PN"1"201;
%"Q_RES"
"1","(-6500,2300)","0","pure_quanta","I2096";
;
LOCATION"R209"
$SEC"1"
CDS_SEC"1"
VALUE"0"
ROOM"RST_CPU0_PLD_TO_DIMM"
PACK_TYPE"0402LF"
PART_NUMBER"CS00002JB38"
TOLERANCE"5%"
MATERIAL"CHIP"
WATTAGE"1/16W"
CDS_LIB"pure_quanta"
BOM_COST"MEM";
"B"
$PN"2"72;
"A"
$PN"1"202;
%"Q_RES"
"1","(-6500,2000)","0","pure_quanta","I2097";
;
LOCATION"R279"
$SEC"1"
CDS_SEC"1"
VALUE"33"
ROOM"RST_CPU0_PLD_TO_DIMM"
PACK_TYPE"0402LF"
PART_NUMBER"CS03302JB29"
TOLERANCE"5%"
MATERIAL"CHIP"
WATTAGE"1/16W"
BOM_COST"MEM"
CDS_LIB"pure_quanta";
"B"
$PN"2"27;
"A"
$PN"1"4;
%"Q_RES"
"1","(-6500,1950)","0","pure_quanta","I2098";
;
LOCATION"R280"
$SEC"1"
CDS_SEC"1"
VALUE"0"
ROOM"RST_CPU0_PLD_TO_DIMM"
PACK_TYPE"0402LF"
PART_NUMBER"CS00002JB38"
TOLERANCE"5%"
MATERIAL"CHIP"
WATTAGE"1/16W"
BOM_COST"MEM"
CDS_LIB"pure_quanta";
"B"
$PN"2"54;
"A"
$PN"1"5;
%"Q_RES"
"1","(-6500,1900)","0","pure_quanta","I2099";
;
LOCATION"R289"
$SEC"1"
CDS_SEC"1"
VALUE"33"
ROOM"RST_CPU0_PLD_TO_DIMM"
PACK_TYPE"0402LF"
PART_NUMBER"CS03302JB29"
TOLERANCE"5%"
MATERIAL"CHIP"
WATTAGE"1/16W"
BOM_COST"MEM"
CDS_LIB"pure_quanta";
"B"
$PN"2"20;
"A"
$PN"1"6;
%"Q_RES"
"1","(-6500,1600)","0","pure_quanta","I2100";
;
LOCATION"R176"
$SEC"1"
CDS_SEC"1"
VALUE"33"
ROOM"RST_CPU0_PLD_TO_DIMM"
PACK_TYPE"0402LF"
PART_NUMBER"CS03302JB29"
TOLERANCE"5%"
MATERIAL"CHIP"
WATTAGE"1/16W"
CDS_LIB"pure_quanta"
BOM_COST"MEM";
"B"
$PN"2"9;
"A"
$PN"1"26;
%"Q_RES"
"1","(-6500,1700)","0","pure_quanta","I2101";
;
LOCATION"R224"
$SEC"1"
CDS_SEC"1"
VALUE"33"
ROOM"RST_CPU0_PLD_TO_DIMM"
PACK_TYPE"0402LF"
PART_NUMBER"CS03302JB29"
TOLERANCE"5%"
MATERIAL"CHIP"
WATTAGE"1/16W"
CDS_LIB"pure_quanta"
BOM_COST"MEM";
"B"
$PN"2"50;
"A"
$PN"1"168;
%"Q_RES"
"1","(-6500,1350)","0","pure_quanta","I2102";
;
LOCATION"R283"
$SEC"1"
CDS_SEC"1"
VALUE"0"
ROOM"RST_CPU0_PLD_TO_DIMM"
PACK_TYPE"0402LF"
PART_NUMBER"CS00002JB38"
TOLERANCE"5%"
MATERIAL"CHIP"
WATTAGE"1/16W"
BOM_COST"MEM"
CDS_LIB"pure_quanta";
"B"
$PN"2"18;
"A"
$PN"1"22;
%"Q_RES"
"1","(-6500,1400)","0","pure_quanta","I2103";
;
LOCATION"R282"
$SEC"1"
CDS_SEC"1"
VALUE"33"
ROOM"RST_CPU0_PLD_TO_DIMM"
PACK_TYPE"0402LF"
PART_NUMBER"CS03302JB29"
TOLERANCE"5%"
MATERIAL"CHIP"
WATTAGE"1/16W"
BOM_COST"MEM"
CDS_LIB"pure_quanta";
"B"
$PN"2"12;
"A"
$PN"1"23;
%"Q_RES"
"1","(-6500,1450)","0","pure_quanta","I2104";
;
LOCATION"R218"
$SEC"1"
CDS_SEC"1"
VALUE"33"
ROOM"RST_CPU0_PLD_TO_DIMM"
PACK_TYPE"0402LF"
PART_NUMBER"CS03302JB29"
TOLERANCE"5%"
MATERIAL"CHIP"
WATTAGE"1/16W"
BOM_COST"MEM"
CDS_LIB"pure_quanta";
"B"
$PN"2"11;
"A"
$PN"1"24;
%"Q_RES"
"1","(-6500,1150)","0","pure_quanta","I2106";
;
LOCATION"R1282"
$SEC"1"
CDS_SEC"1"
VALUE"33"
ROOM"RST_CPU0_PLD_TO_DIMM"
PACK_TYPE"0402LF"
PART_NUMBER"CS03302JB29"
TOLERANCE"5%"
MATERIAL"CHIP"
WATTAGE"1/16W"
CDS_LIB"pure_quanta"
BOM_COST"MEM";
"B"
$PN"2"14;
"A"
$PN"1"25;
%"Q_RES"
"1","(-6500,750)","0","pure_quanta","I2107";
;
LOCATION"R199"
$SEC"1"
CDS_SEC"1"
VALUE"33"
ROOM"RST_CPU0_PLD_TO_DIMM"
PACK_TYPE"0402LF"
PART_NUMBER"CS03302JB29"
TOLERANCE"5%"
MATERIAL"CHIP"
WATTAGE"1/16W"
CDS_LIB"pure_quanta"
BOM_COST"MEM";
"B"
$PN"2"67;
"A"
$PN"1"116;
%"Q_RES"
"1","(-6500,850)","0","pure_quanta","I2108";
;
LOCATION"R1063"
$SEC"1"
CDS_SEC"1"
VALUE"33"
ROOM"RST_CPU0_PLD_TO_DIMM"
PACK_TYPE"0402LF"
PART_NUMBER"CS03302JB29"
TOLERANCE"5%"
MATERIAL"CHIP"
WATTAGE"1/16W"
BOM_COST"MEM"
CDS_LIB"pure_quanta";
"B"
$PN"2"69;
"A"
$PN"1"71;
%"Q_RES"
"1","(-6500,700)","0","pure_quanta","I2110";
;
LOCATION"R482"
$SEC"1"
CDS_SEC"1"
VALUE"33"
ROOM"RST_CPU0_PLD_TO_DIMM"
PACK_TYPE"0402LF"
PART_NUMBER"CS03302JB29"
TOLERANCE"5%"
MATERIAL"CHIP"
WATTAGE"1/16W"
CDS_LIB"pure_quanta"
BOM_COST"MEM";
"B"
$PN"2"66;
"A"
$PN"1"99;
%"Q_RES"
"1","(-6500,450)","0","pure_quanta","I2143";
;
LOCATION"R1052"
$SEC"1"
CDS_SEC"1"
VALUE"33"
ROOM"RST_CPU0_PLD_TO_DIMM"
PACK_TYPE"0402LF"
PART_NUMBER"CS03302JB29"
TOLERANCE"5%"
MATERIAL"CHIP"
WATTAGE"1/16W"
BOM_COST"MEM"
CDS_LIB"pure_quanta";
"B"
$PN"2"84;
"A"
$PN"1"100;
%"LCMXO3D9400HC5BG484C"
"2","(-4425,1675)","0","pure_quanta","I2144";
;
LOCATION"U18"
$SEC"2"
CDS_SEC"2"
VALUE"LCMXO3D-9400HC-5BG484C"
MATERIAL"IC"
PART_TYPE"SMLF"
PART_NUMBER"AJ094000T05"
CDS_LIB"pure_quanta"
NEEDS_NO_SIZE"TRUE"
CDS_LMAN_SYM_OUTLINE"-725,1375,725,-1375";
"PB21D"
$PN"Y10"21;
"PB21C"
$PN"Y9"0;
"PB46D"
$PN"T16"283;
"PB46C"
$PN"V17"0;
"PB44D"
$PN"W18"281;
"PB44C"
$PN"Y19"282;
"PB43D"
$PN"U16"0;
"PB43C"
$PN"T15"260;
"PB41D"
$PN"W17"62;
"PB41C"
$PN"Y18"261;
"PB41B"
$PN"AA18"60;
"PB41A"
$PN"AB18"167;
"PB40D"
$PN"V16"262;
"PB40C"
$PN"Y17"106;
"PB40B"
$PN"AA17"105;
"PB40A"
$PN"AB17"59;
"PB38D"
$PN"U15"166;
"PB38C"
$PN"V15"265;
"PB38B"
$PN"AA16"264;
"PB38A"
$PN"AB16"245;
"PB35D"
$PN"W15"263;
"PB35C"
$PN"Y15"268;
"PB32D"
$PN"V14"279;
"PB32C"
$PN"U14"256;
"PB32B"
$PN"T14"244;
"PB32A"
$PN"T13"58;
"PB33D"
$PN"W14"284;
"PB33C"
$PN"Y14"285;
"PB30D"
$PN"W13"257;
"PB30C"
$PN"Y13"258;
"PB29D"
$PN"U13"109;
"PB29C"
$PN"V13"112;
"PB27D"
$PN"V12"83;
"PB27C"
$PN"U12"84;
"PB27B"
$PN"T12"85;
"PB27A"
$PN"Y12"86;
"PB22D"
$PN"U11"68;
"PB22C"
$PN"T11"69;
"PB19D"
$PN"U10"16;
"PB19C"
$PN"T10"17;
"PB19B"
$PN"AB9"18;
"PB19A"
$PN"AA9"12;
"PB18D"
$PN"W9"11;
"PB18C"
$PN"Y8"13;
"PB16D"
$PN"W8"19;
"PB16C"
$PN"V9"50;
"PB13B"
$PN"AB7"54;
"PB13A"
$PN"AA7"27;
"PB11D"
$PN"V7"3;
"PB11C"
$PN"W6"2;
"PB11B"
$PN"AB6"1;
"PB11A"
$PN"AA6"28;
"PB35B"
$PN"AA15"274;
"PB35A"
$PN"AB15"273;
"PB46B||SI||SISPI"
$PN"AA21"65;
"PB46A||SN"
$PN"AB21"64;
"PB44B"
$PN"AA20"0;
"PB44A"
$PN"AB20"63;
"PB43B"
$PN"AA19"0;
"PB43A"
$PN"AB19"259;
"PB33B"
$PN"AA14"278;
"PB33A"
$PN"AB14"165;
"PB30B"
$PN"AA13"107;
"PB30A"
$PN"AB13"108;
"PB29B||PCLKC2_1"
$PN"AA12"110;
"PB29A||PCLKT2_1"
$PN"AB12"111;
"PB24D"
$PN"Y11"87;
"PB24C"
$PN"V11"0;
"PB24B"
$PN"AB11"66;
"PB24A"
$PN"AA11"67;
"PB22B||PCLKC2_0"
$PN"AB10"70;
"PB22A||PCLKT2_0"
$PN"AA10"0;
"PB21B"
$PN"W10"14;
"PB21A"
$PN"V10"15;
"PB18B"
$PN"AB8"10;
"PB18A"
$PN"AA8"9;
"PB16B||SO||SPISO"
$PN"U9"8;
"PB16A||MCLK||CCLK"
$PN"T9"7;
"PB13D"
$PN"U8"0;
"PB13C"
$PN"V8"20;
"PB10D"
$PN"Y6"0;
"PB10C"
$PN"Y5"72;
"PB10B"
$PN"AB5"196;
"PB10A"
$PN"AA5"51;
"PB8B"
$PN"AB4"102;
"PB8A"
$PN"AA4"80;
"PB8D"
$PN"T8"197;
"PB8C"
$PN"U7"88;
"PB7D"
$PN"W5"113;
"PB7C"
$PN"Y4"114;
"PB7B"
$PN"AB3"73;
"PB7A||CSSPIN"
$PN"AA3"82;
"PB5D"
$PN"U6"103;
"PB5C"
$PN"V6"115;
"PB5B"
$PN"AB2"52;
"PB5A"
$PN"AA2"53;
%"Q_RES"
"1","(-6500,400)","0","pure_quanta","I2145";
;
LOCATION"R648"
$SEC"1"
CDS_SEC"1"
VALUE"33"
ROOM"RST_CPU0_PLD_TO_DIMM"
PACK_TYPE"0402LF"
PART_NUMBER"CS03302JB29"
TOLERANCE"5%"
MATERIAL"CHIP"
WATTAGE"1/16W"
BOM_COST"MEM"
CDS_LIB"pure_quanta";
"B"
$PN"2"83;
"A"
$PN"1"101;
%"Q_RES"
"1","(-2550,2800)","0","pure_quanta","I2162";
;
$LOCATION"R745"
CDS_LOCATION"R745"
$SEC"1"
CDS_SEC"1"
VALUE"0"
CDS_LIB"pure_quanta"
BOM_COST"MEM"
WATTAGE"1/16W"
MATERIAL"CHIP"
TOLERANCE"5%"
PART_NUMBER"CS00002JB38"
PACK_TYPE"0402LF"
ROOM"RST_CPU0_PLD_TO_DIMM";
"B"
$PN"2"254;
"A"
$PN"1"111;
%"Q_RES"
"1","(-2550,2650)","0","pure_quanta","I2164";
;
$LOCATION"R1543"
CDS_LOCATION"R1543"
$SEC"1"
CDS_SEC"1"
VALUE"0"
ROOM"RST_CPU0_PLD_TO_DIMM"
PACK_TYPE"0402LF"
PART_NUMBER"CS00002JB38"
TOLERANCE"5%"
MATERIAL"CHIP"
WATTAGE"1/16W"
BOM_COST"MEM"
CDS_LIB"pure_quanta";
"B"
$PN"2"248;
"A"
$PN"1"109;
%"Q_RES"
"1","(-3150,4850)","0","pure_quanta","I2184";
;
LOCATION"R937"
$SEC"1"
CDS_SEC"1"
VALUE"0"
ROOM"RST_CPU0_PLD_TO_DIMM"
PACK_TYPE"0402LF"
PART_NUMBER"CS00002JB38"
TOLERANCE"5%"
MATERIAL"CHIP"
WATTAGE"1/16W"
BOM_COST"MEM"
CDS_LIB"pure_quanta";
"B"
$PN"2"192;
"A"
$PN"1"181;
%"Q_RES"
"1","(-3150,4900)","0","pure_quanta","I2186";
;
LOCATION"R856"
$SEC"1"
CDS_SEC"1"
VALUE"0"
ROOM"RST_CPU0_PLD_TO_DIMM"
PACK_TYPE"0402LF"
PART_NUMBER"CS00002JB38"
TOLERANCE"5%"
MATERIAL"CHIP"
WATTAGE"1/16W"
BOM_COST"MEM"
CDS_LIB"pure_quanta";
"B"
$PN"2"193;
"A"
$PN"1"208;
%"Q_RES"
"1","(-3150,4950)","0","pure_quanta","I2188";
;
LOCATION"R708"
$SEC"1"
CDS_SEC"1"
VALUE"33"
ROOM"RST_CPU0_PLD_TO_DIMM"
PACK_TYPE"0402LF"
PART_NUMBER"CS03302JB29"
TOLERANCE"5%"
MATERIAL"CHIP"
WATTAGE"1/16W"
BOM_COST"MEM"
CDS_LIB"pure_quanta";
"B"
$PN"2"194;
"A"
$PN"1"212;
%"Q_RES"
"1","(-3150,5150)","0","pure_quanta","I2193";
;
$LOCATION"R1549"
CDS_LOCATION"R1549"
$SEC"1"
CDS_SEC"1"
VALUE"33"
CDS_LIB"pure_quanta"
BOM_COST"MEM"
WATTAGE"1/16W"
MATERIAL"CHIP"
TOLERANCE"5%"
PART_NUMBER"CS03302JB29"
PACK_TYPE"0402LF"
ROOM"RST_CPU0_PLD_TO_DIMM";
"B"
$PN"2"132;
"A"
$PN"1"182;
%"Q_RES"
"1","(-3150,5100)","0","pure_quanta","I2194";
;
$LOCATION"R1550"
CDS_LOCATION"R1550"
$SEC"1"
CDS_SEC"1"
VALUE"33"
ROOM"RST_CPU0_PLD_TO_DIMM"
PACK_TYPE"0402LF"
PART_NUMBER"CS03302JB29"
TOLERANCE"5%"
MATERIAL"CHIP"
WATTAGE"1/16W"
BOM_COST"MEM"
CDS_LIB"pure_quanta";
"B"
$PN"2"133;
"A"
$PN"1"209;
%"Q_RES"
"1","(-3150,5050)","0","pure_quanta","I2195";
;
$LOCATION"R1551"
CDS_LOCATION"R1551"
$SEC"1"
CDS_SEC"1"
VALUE"33"
ROOM"RST_CPU0_PLD_TO_DIMM"
PACK_TYPE"0402LF"
PART_NUMBER"CS03302JB29"
TOLERANCE"5%"
MATERIAL"CHIP"
WATTAGE"1/16W"
BOM_COST"MEM"
CDS_LIB"pure_quanta";
"B"
$PN"2"134;
"A"
$PN"1"210;
%"Q_RES"
"1","(-3150,5000)","0","pure_quanta","I2196";
;
$LOCATION"R1552"
CDS_LOCATION"R1552"
$SEC"1"
CDS_SEC"1"
VALUE"33"
ROOM"RST_CPU0_PLD_TO_DIMM"
PACK_TYPE"0402LF"
PART_NUMBER"CS03302JB29"
TOLERANCE"5%"
MATERIAL"CHIP"
WATTAGE"1/16W"
BOM_COST"MEM"
CDS_LIB"pure_quanta";
"B"
$PN"2"195;
"A"
$PN"1"211;
%"Q_RES"
"1","(-3150,5300)","0","pure_quanta","I2199";
;
$LOCATION"R1553"
CDS_LOCATION"R1553"
$SEC"1"
CDS_SEC"1"
VALUE"33"
CDS_LIB"pure_quanta"
PACK_TYPE"0402LF"
PART_NUMBER"CS03302JB29"
TOLERANCE"5%"
MATERIAL"CHIP"
WATTAGE"1/16W";
"B"
$PN"2"129;
"A"
$PN"1"176;
%"Q_RES"
"1","(-6350,4850)","0","pure_quanta","I2201";
;
LOCATION"R159"
$SEC"1"
CDS_SEC"1"
VALUE"33"
ROOM"RST_CPU0_PLD_TO_DIMM"
PACK_TYPE"0402LF"
PART_NUMBER"CS03302JB29"
TOLERANCE"5%"
MATERIAL"CHIP"
WATTAGE"1/16W"
BOM_COST"MEM"
CDS_LIB"pure_quanta";
"B"
$PN"2"188;
"A"
$PN"1"220;
%"Q_RES"
"1","(-3150,5350)","0","pure_quanta","I2203";
;
$LOCATION"R1556"
CDS_LOCATION"R1556"
$SEC"1"
CDS_SEC"1"
VALUE"33"
WATTAGE"1/16W"
MATERIAL"CHIP"
TOLERANCE"5%"
PART_NUMBER"CS03302JB29"
PACK_TYPE"0402LF"
CDS_LIB"pure_quanta";
"B"
$PN"2"169;
"A"
$PN"1"175;
%"Q_RES"
"1","(-3150,5250)","0","pure_quanta","I2205";
;
$LOCATION"R1557"
CDS_LOCATION"R1557"
$SEC"1"
CDS_SEC"1"
VALUE"33"
CDS_LIB"pure_quanta"
PACK_TYPE"0402LF"
PART_NUMBER"CS03302JB29"
TOLERANCE"5%"
MATERIAL"CHIP"
WATTAGE"1/16W";
"B"
$PN"2"130;
"A"
$PN"1"177;
%"Q_RES"
"1","(-3150,5200)","0","pure_quanta","I2207";
;
$LOCATION"R1558"
CDS_LOCATION"R1558"
$SEC"1"
CDS_SEC"1"
VALUE"33"
WATTAGE"1/16W"
MATERIAL"CHIP"
TOLERANCE"5%"
PART_NUMBER"CS03302JB29"
PACK_TYPE"0402LF"
CDS_LIB"pure_quanta";
"B"
$PN"2"131;
"A"
$PN"1"158;
%"Q_RES"
"1","(-6500,2500)","0","pure_quanta","I2209";
;
$LOCATION"R1563"
CDS_LOCATION"R1563"
$SEC"1"
CDS_SEC"1"
VALUE"33"
BOM_COST"MEM"
WATTAGE"1/16W"
MATERIAL"CHIP"
TOLERANCE"5%"
PART_NUMBER"CS03302JB29"
PACK_TYPE"0402LF"
ROOM"RST_CPU0_PLD_TO_DIMM"
CDS_LIB"pure_quanta";
"B"
$PN"2"88;
"A"
$PN"1"200;
%"Q_RES"
"1","(-3150,4150)","0","pure_quanta","I2211";
;
LOCATION"R1564"
$SEC"1"
CDS_SEC"1"
VALUE"33"
CDS_LIB"pure_quanta"
BOM_COST"MEM"
WATTAGE"1/16W"
MATERIAL"CHIP"
TOLERANCE"5%"
PART_NUMBER"CS03302JB29"
PACK_TYPE"0402LF"
ROOM"RST_CPU0_PLD_TO_DIMM";
"B"
$PN"2"120;
"A"
$PN"1"43;
%"Q_RES"
"1","(-3150,4100)","0","pure_quanta","I2213";
;
$LOCATION"R1616"
CDS_LOCATION"R1616"
$SEC"1"
CDS_SEC"1"
VALUE"33"
ROOM"RST_CPU0_PLD_TO_DIMM"
PACK_TYPE"0402LF"
PART_NUMBER"CS03302JB29"
TOLERANCE"5%"
MATERIAL"CHIP"
WATTAGE"1/16W"
BOM_COST"MEM"
CDS_LIB"pure_quanta";
"B"
$PN"2"119;
"A"
$PN"1"45;
%"Q_RES"
"1","(-3150,3950)","0","pure_quanta","I2215";
;
LOCATION"R195"
$SEC"1"
CDS_SEC"1"
VALUE"0"
CDS_LIB"pure_quanta"
BOM_COST"MEM"
WATTAGE"1/16W"
MATERIAL"CHIP"
TOLERANCE"5%"
PART_NUMBER"CS00002JB38"
PACK_TYPE"0402LF"
ROOM"RST_CPU0_PLD_TO_DIMM";
"B"
$PN"2"44;
"A"
$PN"1"48;
%"Q_RES"
"1","(-3150,3900)","0","pure_quanta","I2217";
;
LOCATION"R252"
$SEC"1"
CDS_SEC"1"
VALUE"0"
ROOM"RST_CPU0_PLD_TO_DIMM"
PACK_TYPE"0402LF"
PART_NUMBER"CS00002JB38"
TOLERANCE"5%"
MATERIAL"CHIP"
WATTAGE"1/16W"
BOM_COST"MEM"
CDS_LIB"pure_quanta";
"B"
$PN"2"33;
"A"
$PN"1"34;
END.
